(kicad_pcb
	(version 20241229)
	(generator "pcbnew")
	(generator_version "9.0")
	(general
		(thickness 1.294)
		(legacy_teardrops no)
	)
	(paper "A3")
	(title_block
		(title "Kintex 410T devboard")
		(date "2024-04-03")
		(rev "1.1.2")
		(comment 9 "footprint 170 of 975 (U1), pads 182-239 of 900")
	)
	(layers
		(0 "F.Cu" mixed)
		(4 "In1.Cu" power)
		(6 "In2.Cu" power)
		(8 "In3.Cu" mixed)
		(10 "In4.Cu" power)
		(12 "In5.Cu" mixed)
		(14 "In6.Cu" power)
		(16 "In7.Cu" mixed)
		(18 "In8.Cu" power)
		(2 "B.Cu" mixed)
		(9 "F.Adhes" user "F.Adhesive")
		(11 "B.Adhes" user "B.Adhesive")
		(13 "F.Paste" user)
		(15 "B.Paste" user)
		(5 "F.SilkS" user "F.Silkscreen")
		(7 "B.SilkS" user "B.Silkscreen")
		(1 "F.Mask" user)
		(3 "B.Mask" user)
		(17 "Dwgs.User" user "User.Drawings")
		(19 "Cmts.User" user "User.Comments")
		(21 "Eco1.User" user "User.Eco1")
		(23 "Eco2.User" user "User.Eco2")
		(25 "Edge.Cuts" user)
		(27 "Margin" user)
		(31 "F.CrtYd" user "F.Courtyard")
		(29 "B.CrtYd" user "B.Courtyard")
		(35 "F.Fab" user)
		(33 "B.Fab" user)
	)
	(footprint "antmicro-footprints:BGA-900_31x31mm_Layout30x30_P1x1mm_FFG900"
		(locked yes)
		(layer "F.Cu")
		(at 200 130)
		(property "Reference" "U1"
			(at -15.74 -15.78 0)
			(layer "F.SilkS")
			(effects
				(font
					(size 0.7 0.7)
					(thickness 0.15)
				)
				(justify left bottom)
			)
		)
		(property "Value" "XC7K410T-2FFG900I"
			(at -4.436 17.635 0)
			(layer "F.Fab")
			(effects
				(font
					(size 0.7 0.7)
					(thickness 0.15)
				)
				(justify left bottom)
			)
		)
		(property "Description" "FPGA, Kintex-7, MMCM, PLL, 350 I/O's, 710 MHz, 406720 Cells, 970 mV to 1.03 V, FCBGA-900"
			(at 0 0 0)
			(layer "F.Fab")
			(hide yes)
			(effects
				(font
					(size 1.27 1.27)
					(thickness 0.15)
				)
			)
		)
		(property "Author" "Antmicro"
			(at 0 0 0)
			(layer "F.Fab")
			(hide yes)
			(effects
				(font
					(size 1 1)
					(thickness 0.15)
				)
			)
		)
		(property "License" "Apache-2.0"
			(at 0 0 0)
			(layer "F.Fab")
			(hide yes)
			(effects
				(font
					(size 1 1)
					(thickness 0.15)
				)
			)
		)
		(property "MPN" "XC7K410T-2FFG900I"
			(at 0 0 0)
			(layer "F.Fab")
			(hide yes)
			(effects
				(font
					(size 1 1)
					(thickness 0.15)
				)
			)
		)
		(property "Manufacturer" "AMD-Xilinx"
			(at 0 0 0)
			(layer "F.Fab")
			(hide yes)
			(effects
				(font
					(size 1 1)
					(thickness 0.15)
				)
			)
		)
		(sheetname "FPGA supply")
		(sheetfile "fpga-supply.kicad_sch")
		(attr smd)
		(pad "AF2" smd circle
			(at -13.5 10.5)
			(size 0.5 0.5)
			(property pad_prop_bga)
			(layers "F.Cu" "F.Mask" "F.Paste")
			(net 536 "/DRAM + SRAM/DDR.A5")
			(pinfunction "IO_L7N_T1_34")
			(pintype "bidirectional")
			(die_length 21.199)
			(solder_mask_margin 0.02)
		)
		(pad "AF3" smd circle
			(at -12.5 10.5)
			(size 0.5 0.5)
			(property pad_prop_bga)
			(layers "F.Cu" "F.Mask" "F.Paste")
			(net 537 "/DRAM + SRAM/DDR.A6")
			(pinfunction "IO_L7P_T1_34")
			(pintype "bidirectional")
			(die_length 20.914)
			(solder_mask_margin 0.02)
		)
		(pad "AF4" smd circle
			(at -11.5 10.5)
			(size 0.5 0.5)
			(property pad_prop_bga)
			(layers "F.Cu" "F.Mask" "F.Paste")
			(net 25 "+1V35")
			(pinfunction "VCCO_34")
			(pintype "passive")
			(solder_mask_margin 0.02)
		)
		(pad "AF5" smd circle
			(at -10.5 10.5)
			(size 0.5 0.5)
			(property pad_prop_bga)
			(layers "F.Cu" "F.Mask" "F.Paste")
			(net 547 "/DRAM + SRAM/DDR.BA0")
			(pinfunction "IO_L11N_T1_SRCC_34")
			(pintype "bidirectional")
			(die_length 21.528)
			(solder_mask_margin 0.02)
		)
		(pad "AF6" smd circle
			(at -9.5 10.5)
			(size 0.5 0.5)
			(property pad_prop_bga)
			(layers "F.Cu" "F.Mask" "F.Paste")
			(net 559 "/DRAM + SRAM/DDR.~{CAS}")
			(pinfunction "IO_L12P_T1_MRCC_34")
			(pintype "bidirectional")
			(die_length 20.428)
			(solder_mask_margin 0.02)
		)
		(pad "AF7" smd circle
			(at -8.5 10.5)
			(size 0.5 0.5)
			(property pad_prop_bga)
			(layers "F.Cu" "F.Mask" "F.Paste")
			(net 654 "/DRAM + SRAM/DDR.DQ7")
			(pinfunction "IO_L20P_T3_34")
			(pintype "bidirectional")
			(die_length 21.476)
			(solder_mask_margin 0.02)
		)
		(pad "AF8" smd circle
			(at -7.5 10.5)
			(size 0.5 0.5)
			(property pad_prop_bga)
			(layers "F.Cu" "F.Mask" "F.Paste")
			(net 557 "/DRAM + SRAM/DDR.DM")
			(pinfunction "IO_L19P_T3_34")
			(pintype "bidirectional")
			(die_length 18.874)
			(solder_mask_margin 0.02)
		)
		(pad "AF9" smd circle
			(at -6.5 10.5)
			(size 0.5 0.5)
			(property pad_prop_bga)
			(layers "F.Cu" "F.Mask" "F.Paste")
			(net 1 "GND")
			(pinfunction "GND")
			(pintype "passive")
			(solder_mask_margin 0.02)
		)
		(pad "AF10" smd circle
			(at -5.5 10.5)
			(size 0.5 0.5)
			(property pad_prop_bga)
			(layers "F.Cu" "F.Mask" "F.Paste")
			(net 435 "unconnected-(U1E-IO_L14N_T2_SRCC_33-PadAF10)")
			(pinfunction "IO_L14N_T2_SRCC_33")
			(pintype "bidirectional+no_connect")
			(die_length 15.658)
			(solder_mask_margin 0.02)
		)
		(pad "AF11" smd circle
			(at -4.5 10.5)
			(size 0.5 0.5)
			(property pad_prop_bga)
			(layers "F.Cu" "F.Mask" "F.Paste")
			(net 397 "/FPGA Bank 33 & 34/SD_CARD.DAT1")
			(pinfunction "IO_L11N_T1_SRCC_33")
			(pintype "bidirectional")
			(die_length 18.351)
			(solder_mask_margin 0.02)
		)
		(pad "AF12" smd circle
			(at -3.5 10.5)
			(size 0.5 0.5)
			(property pad_prop_bga)
			(layers "F.Cu" "F.Mask" "F.Paste")
			(net 436 "unconnected-(U1E-IO_L23P_T3_33-PadAF12)")
			(pinfunction "IO_L23P_T3_33")
			(pintype "bidirectional+no_connect")
			(die_length 20.111)
			(solder_mask_margin 0.02)
		)
		(pad "AF13" smd circle
			(at -2.5 10.5)
			(size 0.5 0.5)
			(property pad_prop_bga)
			(layers "F.Cu" "F.Mask" "F.Paste")
			(net 407 "/FPGA Bank 33 & 34/USR_FLASH_0.~{CS}")
			(pinfunction "IO_L19N_T3_VREF_33")
			(pintype "bidirectional")
			(die_length 19.268)
			(solder_mask_margin 0.02)
		)
		(pad "AF14" smd circle
			(at -1.5 10.5)
			(size 0.5 0.5)
			(property pad_prop_bga)
			(layers "F.Cu" "F.Mask" "F.Paste")
			(net 26 "+1V8")
			(pinfunction "VCCO_32")
			(pintype "passive")
			(solder_mask_margin 0.02)
		)
		(pad "AF15" smd circle
			(at -0.5 10.5)
			(size 0.5 0.5)
			(property pad_prop_bga)
			(layers "F.Cu" "F.Mask" "F.Paste")
			(net 615 "unconnected-(U1D-IO_L4P_T0_32-PadAF15)")
			(pinfunction "IO_L4P_T0_32")
			(pintype "bidirectional+no_connect")
			(die_length 18.766)
			(solder_mask_margin 0.02)
		)
		(pad "AF16" smd circle
			(at 0.5 10.5)
			(size 0.5 0.5)
			(property pad_prop_bga)
			(layers "F.Cu" "F.Mask" "F.Paste")
			(net 616 "/FPGA Bank 12 & 13/USB_USER.SPD")
			(pinfunction "IO_L6N_T0_VREF_32")
			(pintype "bidirectional")
			(die_length 17.245)
			(solder_mask_margin 0.02)
		)
		(pad "AF17" smd circle
			(at 1.5 10.5)
			(size 0.5 0.5)
			(property pad_prop_bga)
			(layers "F.Cu" "F.Mask" "F.Paste")
			(net 617 "unconnected-(U1D-IO_L12P_T1_MRCC_32-PadAF17)")
			(pinfunction "IO_L12P_T1_MRCC_32")
			(pintype "bidirectional+no_connect")
			(die_length 19.799)
			(solder_mask_margin 0.02)
		)
		(pad "AF18" smd circle
			(at 2.5 10.5)
			(size 0.5 0.5)
			(property pad_prop_bga)
			(layers "F.Cu" "F.Mask" "F.Paste")
			(net 517 "/FPGA Bank 18 & 32/ETH_RMII.RX_DV")
			(pinfunction "IO_L11P_T1_SRCC_32")
			(pintype "bidirectional")
			(die_length 20.405)
			(solder_mask_margin 0.02)
		)
		(pad "AF19" smd circle
			(at 3.5 10.5)
			(size 0.5 0.5)
			(property pad_prop_bga)
			(layers "F.Cu" "F.Mask" "F.Paste")
			(net 1 "GND")
			(pinfunction "GND")
			(pintype "passive")
			(solder_mask_margin 0.02)
		)
		(pad "AF20" smd circle
			(at 4.5 10.5)
			(size 0.5 0.5)
			(property pad_prop_bga)
			(layers "F.Cu" "F.Mask" "F.Paste")
			(net 480 "/FPGA Bank 12 & 13/CW_HEADER.TPDIC")
			(pinfunction "IO_L19P_T3_12")
			(pintype "bidirectional")
			(die_length 9.781)
			(solder_mask_margin 0.02)
		)
		(pad "AF21" smd circle
			(at 5.5 10.5)
			(size 0.5 0.5)
			(property pad_prop_bga)
			(layers "F.Cu" "F.Mask" "F.Paste")
			(net 475 "/FPGA Bank 12 & 13/CW_HEADER.MISO")
			(pinfunction "IO_L19N_T3_VREF_12")
			(pintype "bidirectional")
			(die_length 10.006)
			(solder_mask_margin 0.02)
		)
		(pad "AF22" smd circle
			(at 6.5 10.5)
			(size 0.5 0.5)
			(property pad_prop_bga)
			(layers "F.Cu" "F.Mask" "F.Paste")
			(net 488 "/FPGA Bank 12 & 13/CW_HEADER.HS2")
			(pinfunction "IO_L13P_T2_MRCC_12")
			(pintype "bidirectional")
			(die_length 11.098)
			(solder_mask_margin 0.02)
		)
		(pad "AF23" smd circle
			(at 7.5 10.5)
			(size 0.5 0.5)
			(property pad_prop_bga)
			(layers "F.Cu" "F.Mask" "F.Paste")
			(net 1361 "/SUP_MCU.A4")
			(pinfunction "IO_L11N_T1_SRCC_12")
			(pintype "bidirectional")
			(die_length 10.641)
			(solder_mask_margin 0.02)
		)
		(pad "AF24" smd circle
			(at 8.5 10.5)
			(size 0.5 0.5)
			(property pad_prop_bga)
			(layers "F.Cu" "F.Mask" "F.Paste")
			(net 24 "+3V3")
			(pinfunction "VCCO_12")
			(pintype "passive")
			(solder_mask_margin 0.02)
		)
		(pad "AF25" smd circle
			(at 9.5 10.5)
			(size 0.5 0.5)
			(property pad_prop_bga)
			(layers "F.Cu" "F.Mask" "F.Paste")
			(net 1362 "/SUP_MCU.A6")
			(pinfunction "IO_L16N_T2_12")
			(pintype "bidirectional")
			(die_length 14.464)
			(solder_mask_margin 0.02)
		)
		(pad "AF26" smd circle
			(at 10.5 10.5)
			(size 0.5 0.5)
			(property pad_prop_bga)
			(layers "F.Cu" "F.Mask" "F.Paste")
			(net 571 "/FPGA Bank 12 & 13/~{PB_CTRL_CLR}")
			(pinfunction "IO_L23P_T3_13")
			(pintype "bidirectional")
			(die_length 15.71)
			(solder_mask_margin 0.02)
		)
		(pad "AF27" smd circle
			(at 11.5 10.5)
			(size 0.5 0.5)
			(property pad_prop_bga)
			(layers "F.Cu" "F.Mask" "F.Paste")
			(net 572 "/FPGA Bank 12 & 13/~{PB_CTRL_INT}")
			(pinfunction "IO_L23N_T3_13")
			(pintype "bidirectional")
			(die_length 16.589)
			(solder_mask_margin 0.02)
		)
		(pad "AF28" smd circle
			(at 12.5 10.5)
			(size 0.5 0.5)
			(property pad_prop_bga)
			(layers "F.Cu" "F.Mask" "F.Paste")
			(net 458 "/FPGA Bank 12 & 13/PMOD_A.IO3")
			(pinfunction "IO_L14N_T2_SRCC_13")
			(pintype "bidirectional")
			(die_length 18.857)
			(solder_mask_margin 0.02)
		)
		(pad "AF29" smd circle
			(at 13.5 10.5)
			(size 0.5 0.5)
			(property pad_prop_bga)
			(layers "F.Cu" "F.Mask" "F.Paste")
			(net 1 "GND")
			(pinfunction "GND")
			(pintype "passive")
			(solder_mask_margin 0.02)
		)
		(pad "AF30" smd circle
			(at 14.5 10.5)
			(size 0.5 0.5)
			(property pad_prop_bga)
			(layers "F.Cu" "F.Mask" "F.Paste")
			(net 618 "unconnected-(U1A-IO_L16N_T2_13-PadAF30)")
			(pinfunction "IO_L16N_T2_13")
			(pintype "bidirectional+no_connect")
			(die_length 19.947)
			(solder_mask_margin 0.02)
		)
		(pad "AG1" smd circle
			(at -14.5 11.5)
			(size 0.5 0.5)
			(property pad_prop_bga)
			(layers "F.Cu" "F.Mask" "F.Paste")
			(net 25 "+1V35")
			(pinfunction "VCCO_34")
			(pintype "passive")
			(solder_mask_margin 0.02)
		)
		(pad "AG2" smd circle
			(at -13.5 11.5)
			(size 0.5 0.5)
			(property pad_prop_bga)
			(layers "F.Cu" "F.Mask" "F.Paste")
			(net 558 "/DRAM + SRAM/DDR.~{WE}")
			(pinfunction "IO_L15P_T2_DQS_34")
			(pintype "bidirectional")
			(die_length 22.704)
			(solder_mask_margin 0.02)
		)
		(pad "AG3" smd circle
			(at -12.5 11.5)
			(size 0.5 0.5)
			(property pad_prop_bga)
			(layers "F.Cu" "F.Mask" "F.Paste")
			(net 532 "/DRAM + SRAM/DDR.A1")
			(pinfunction "IO_L9N_T1_DQS_34")
			(pintype "bidirectional")
			(die_length 23.545)
			(solder_mask_margin 0.02)
		)
		(pad "AG4" smd circle
			(at -11.5 11.5)
			(size 0.5 0.5)
			(property pad_prop_bga)
			(layers "F.Cu" "F.Mask" "F.Paste")
			(net 533 "/DRAM + SRAM/DDR.A2")
			(pinfunction "IO_L9P_T1_DQS_34")
			(pintype "bidirectional")
			(die_length 23.769)
			(solder_mask_margin 0.02)
		)
		(pad "AG5" smd circle
			(at -10.5 11.5)
			(size 0.5 0.5)
			(property pad_prop_bga)
			(layers "F.Cu" "F.Mask" "F.Paste")
			(net 560 "/DRAM + SRAM/DDR.~{RAS}")
			(pinfunction "IO_L12N_T1_MRCC_34")
			(pintype "bidirectional")
			(die_length 20.454)
			(solder_mask_margin 0.02)
		)
		(pad "AG6" smd circle
			(at -9.5 11.5)
			(size 0.5 0.5)
			(property pad_prop_bga)
			(layers "F.Cu" "F.Mask" "F.Paste")
			(net 1 "GND")
			(pinfunction "GND")
			(pintype "passive")
			(solder_mask_margin 0.02)
		)
		(pad "AG7" smd circle
			(at -8.5 11.5)
			(size 0.5 0.5)
			(property pad_prop_bga)
			(layers "F.Cu" "F.Mask" "F.Paste")
			(net 655 "/DRAM + SRAM/DDR.DQ4")
			(pinfunction "IO_L20N_T3_34")
			(pintype "bidirectional")
			(die_length 21.497)
			(solder_mask_margin 0.02)
		)
		(pad "AG8" smd circle
			(at -7.5 11.5)
			(size 0.5 0.5)
			(property pad_prop_bga)
			(layers "F.Cu" "F.Mask" "F.Paste")
			(net 11 "+0V675_VREF")
			(pinfunction "IO_L19N_T3_VREF_34")
			(pintype "bidirectional")
			(die_length 15.362)
			(solder_mask_margin 0.02)
		)
		(pad "AG9" smd circle
			(at -6.5 11.5)
			(size 0.5 0.5)
			(property pad_prop_bga)
			(layers "F.Cu" "F.Mask" "F.Paste")
			(net 443 "unconnected-(U1E-IO_L16P_T2_33-PadAG9)")
			(pinfunction "IO_L16P_T2_33")
			(pintype "bidirectional+no_connect")
			(die_length 15.472)
			(solder_mask_margin 0.02)
		)
		(pad "AG10" smd circle
			(at -5.5 11.5)
			(size 0.5 0.5)
			(property pad_prop_bga)
			(layers "F.Cu" "F.Mask" "F.Paste")
			(net 447 "unconnected-(U1E-IO_L13P_T2_MRCC_33-PadAG10)")
			(pinfunction "IO_L13P_T2_MRCC_33")
			(pintype "bidirectional+no_connect")
			(die_length 19.427)
			(solder_mask_margin 0.02)
		)
		(pad "AG11" smd circle
			(at -4.5 11.5)
			(size 0.5 0.5)
			(property pad_prop_bga)
			(layers "F.Cu" "F.Mask" "F.Paste")
			(net 26 "+1V8")
			(pinfunction "VCCO_33")
			(pintype "passive")
			(solder_mask_margin 0.02)
		)
		(pad "AG12" smd circle
			(at -3.5 11.5)
			(size 0.5 0.5)
			(property pad_prop_bga)
			(layers "F.Cu" "F.Mask" "F.Paste")
			(net 448 "unconnected-(U1E-IO_L23N_T3_33-PadAG12)")
			(pinfunction "IO_L23N_T3_33")
			(pintype "bidirectional+no_connect")
			(die_length 20.042)
			(solder_mask_margin 0.02)
		)
		(pad "AG13" smd circle
			(at -2.5 11.5)
			(size 0.5 0.5)
			(property pad_prop_bga)
			(layers "F.Cu" "F.Mask" "F.Paste")
			(net 402 "/FPGA Bank 33 & 34/USR_FLASH_0.DQ3")
			(pinfunction "IO_L24P_T3_33")
			(pintype "bidirectional")
			(die_length 20.152)
			(solder_mask_margin 0.02)
		)
		(pad "AG14" smd circle
			(at -1.5 11.5)
			(size 0.5 0.5)
			(property pad_prop_bga)
			(layers "F.Cu" "F.Mask" "F.Paste")
			(net 498 "/FPGA Bank 12 & 13/USB_USER.~{OE}")
			(pinfunction "IO_L4N_T0_32")
			(pintype "bidirectional")
			(die_length 19.861)
			(solder_mask_margin 0.02)
		)
		(pad "AG15" smd circle
			(at -0.5 11.5)
			(size 0.5 0.5)
			(property pad_prop_bga)
			(layers "F.Cu" "F.Mask" "F.Paste")
			(net 619 "/FPGA Bank 12 & 13/USB_USER.SCON")
			(pinfunction "IO_L2P_T0_32")
			(pintype "bidirectional")
			(die_length 19.43)
			(solder_mask_margin 0.02)
		)
		(pad "AG16" smd circle
			(at 0.5 11.5)
			(size 0.5 0.5)
			(property pad_prop_bga)
			(layers "F.Cu" "F.Mask" "F.Paste")
			(net 1 "GND")
			(pinfunction "GND")
			(pintype "passive")
			(solder_mask_margin 0.02)
		)
		(pad "AG17" smd circle
			(at 1.5 11.5)
			(size 0.5 0.5)
			(property pad_prop_bga)
			(layers "F.Cu" "F.Mask" "F.Paste")
			(net 620 "unconnected-(U1D-IO_L12N_T1_MRCC_32-PadAG17)")
			(pinfunction "IO_L12N_T1_MRCC_32")
			(pintype "bidirectional+no_connect")
			(die_length 19.963)
			(solder_mask_margin 0.02)
		)
		(pad "AG18" smd circle
			(at 2.5 11.5)
			(size 0.5 0.5)
			(property pad_prop_bga)
			(layers "F.Cu" "F.Mask" "F.Paste")
			(net 621 "unconnected-(U1D-IO_L11N_T1_SRCC_32-PadAG18)")
			(pinfunction "IO_L11N_T1_SRCC_32")
			(pintype "bidirectional+no_connect")
			(die_length 20.178)
			(solder_mask_margin 0.02)
		)
		(pad "AG19" smd circle
			(at 3.5 11.5)
			(size 0.5 0.5)
			(property pad_prop_bga)
			(layers "F.Cu" "F.Mask" "F.Paste")
			(net 626 "unconnected-(U1D-IO_L8P_T1_32-PadAG19)")
			(pinfunction "IO_L8P_T1_32")
			(pintype "bidirectional+no_connect")
			(die_length 22.281)
			(solder_mask_margin 0.02)
		)
		(pad "AG20" smd circle
			(at 4.5 11.5)
			(size 0.5 0.5)
			(property pad_prop_bga)
			(layers "F.Cu" "F.Mask" "F.Paste")
			(net 485 "/FPGA Bank 12 & 13/CW_HEADER.TPDID")
			(pinfunction "IO_L22P_T3_12")
			(pintype "bidirectional")
			(die_length 10.048)
			(solder_mask_margin 0.02)
		)
		(pad "AG21" smd circle
			(at 5.5 11.5)
			(size 0.5 0.5)
			(property pad_prop_bga)
			(layers "F.Cu" "F.Mask" "F.Paste")
			(net 24 "+3V3")
			(pinfunction "VCCO_12")
			(pintype "passive")
			(solder_mask_margin 0.02)
		)
		(pad "AG22" smd circle
			(at 6.5 11.5)
			(size 0.5 0.5)
			(property pad_prop_bga)
			(layers "F.Cu" "F.Mask" "F.Paste")
			(net 493 "/FPGA Bank 12 & 13/CW_HEADER.IO4")
			(pinfunction "IO_L20P_T3_12")
			(pintype "bidirectional")
			(die_length 9.529)
			(solder_mask_margin 0.02)
		)
		(pad "AG23" smd circle
			(at 7.5 11.5)
			(size 0.5 0.5)
			(property pad_prop_bga)
			(layers "F.Cu" "F.Mask" "F.Paste")
			(net 1330 "/SUP_MCU.RX1")
			(pinfunction "IO_L13N_T2_MRCC_12")
			(pintype "bidirectional")
			(die_length 11.265)
			(solder_mask_margin 0.02)
		)
		(pad "AG24" smd circle
			(at 8.5 11.5)
			(size 0.5 0.5)
			(property pad_prop_bga)
			(layers "F.Cu" "F.Mask" "F.Paste")
			(net 1390 "/SUP_MCU.RD")
			(pinfunction "IO_L14P_T2_SRCC_12")
			(pintype "bidirectional")
			(die_length 11.801)
			(solder_mask_margin 0.02)
		)
		(pad "AG25" smd circle
			(at 9.5 11.5)
			(size 0.5 0.5)
			(property pad_prop_bga)
			(layers "F.Cu" "F.Mask" "F.Paste")
			(net 487 "/FPGA Bank 12 & 13/CW_HEADER.HS1")
			(pinfunction "IO_L18P_T2_12")
			(pintype "bidirectional")
			(die_length 14.835)
			(solder_mask_margin 0.02)
		)
		(pad "AG26" smd circle
			(at 10.5 11.5)
			(size 0.5 0.5)
			(property pad_prop_bga)
			(layers "F.Cu" "F.Mask" "F.Paste")
			(net 1 "GND")
			(pinfunction "GND")
			(pintype "passive")
			(solder_mask_margin 0.02)
		)
		(pad "AG27" smd circle
			(at 11.5 11.5)
			(size 0.5 0.5)
			(property pad_prop_bga)
			(layers "F.Cu" "F.Mask" "F.Paste")
			(net 569 "/FPGA Bank 12 & 13/USB_HOST.VBUS_PEN")
			(pinfunction "IO_L21P_T3_DQS_13")
			(pintype "bidirectional")
			(die_length 17.137)
			(solder_mask_margin 0.02)
		)
		(pad "AG28" smd circle
			(at 12.5 11.5)
			(size 0.5 0.5)
			(property pad_prop_bga)
			(layers "F.Cu" "F.Mask" "F.Paste")
			(net 631 "unconnected-(U1A-IO_L21N_T3_DQS_13-PadAG28)")
			(pinfunction "IO_L21N_T3_DQS_13")
			(pintype "bidirectional+no_connect")
			(die_length 16.984)
			(solder_mask_margin 0.02)
		)
		(pad "AG29" smd circle
			(at 13.5 11.5)
			(size 0.5 0.5)
			(property pad_prop_bga)
			(layers "F.Cu" "F.Mask" "F.Paste")
			(net 632 "unconnected-(U1A-IO_L13P_T2_MRCC_13-PadAG29)")
			(pinfunction "IO_L13P_T2_MRCC_13")
			(pintype "bidirectional+no_connect")
			(die_length 18.893)
			(solder_mask_margin 0.02)
		)
	)
)
